(kicad_pcb
	(version 20260206)
	(generator "pcbnew")
	(generator_version "10.0")
	(general
		(thickness 1.6)
		(legacy_teardrops no)
	)
	(paper "A4")
	(title_block
		(title "04192023_DAF0TMB3IC0_F0TG_MB_C_brd_V02_OCP.brd")
		(comment 1 "Grand Teton / footprints 2378-2384 of 8354")
	)
	(layers
		(0 "F.Cu" signal "TOP")
		(4 "In1.Cu" signal "GND")
		(6 "In2.Cu" signal "IN1")
		(8 "In3.Cu" signal "GND1")
		(10 "In4.Cu" signal "IN2")
		(12 "In5.Cu" signal "GND2")
		(14 "In6.Cu" signal "IN3")
		(16 "In7.Cu" signal "GND3")
		(18 "In8.Cu" signal "VCC")
		(20 "In9.Cu" signal "VCC1")
		(22 "In10.Cu" signal "GND4")
		(24 "In11.Cu" signal "IN4")
		(26 "In12.Cu" signal "GND5")
		(28 "In13.Cu" signal "IN5")
		(30 "In14.Cu" signal "GND6")
		(32 "In15.Cu" signal "IN6")
		(34 "In16.Cu" signal "GND7")
		(2 "B.Cu" signal "BOTTOM")
		(9 "F.Adhes" user "F.Adhesive")
		(11 "B.Adhes" user "B.Adhesive")
		(13 "F.Paste" user "Package Geometry/Pastemask Top")
		(15 "B.Paste" user "Package Geometry/Pastemask Bottom")
		(5 "F.SilkS" user "Ref Des/Silkscreen Top")
		(7 "B.SilkS" user "Ref Des/Silkscreen Bottom")
		(1 "F.Mask" user "Board Geometry/Soldermask Top")
		(3 "B.Mask" user "Board Geometry/Soldermask Bottom")
		(17 "Dwgs.User" user "User.Drawings")
		(19 "Cmts.User" user "User.Comments")
		(21 "Eco1.User" user "User.Eco1")
		(23 "Eco2.User" user "User.Eco2")
		(25 "Edge.Cuts" user "Board Geometry/Outline")
		(27 "Margin" user)
		(31 "F.CrtYd" user "Package Geometry/Place Bound Top")
		(29 "B.CrtYd" user "Package Geometry/Place Bound Bottom")
		(35 "F.Fab" user "Ref Des/Assembly Top")
		(33 "B.Fab" user "Ref Des/Assembly Bottom")
	)
	(footprint ""
		(layer "F.Cu")
		(at 62.339728 -53.693314)
		(property "Reference" "U9051"
			(at -4.14782 2.455672 0)
			(unlocked yes)
			(layer "F.SilkS")
			(effects
				(font
					(size 0.7874 0.5842)
					(thickness 0.1524)
				)
				(justify left)
			)
		)
		(property "Value" ""
			(at 0 0 0)
			(layer "F.Fab")
			(effects
				(font
					(size 1.27 1.27)
				)
			)
		)
		(duplicate_pad_numbers_are_jumpers no)
		(fp_line
			(start -1.733296 -1.549908)
			(end -1.733296 1.549908)
			(stroke
				(width 0.1524)
				(type default)
			)
			(layer "F.SilkS")
		)
		(fp_line
			(start -1.733296 1.549908)
			(end 1.733296 1.549908)
			(stroke
				(width 0.1524)
				(type default)
			)
			(layer "F.SilkS")
		)
		(fp_line
			(start -0.660908 -1.549908)
			(end -1.733296 -1.549908)
			(stroke
				(width 0.1524)
				(type default)
			)
			(layer "F.SilkS")
		)
		(fp_line
			(start 0 -0.889)
			(end -0.660908 -1.549908)
			(stroke
				(width 0.1524)
				(type default)
			)
			(layer "F.SilkS")
		)
		(fp_line
			(start 0.660908 -1.549908)
			(end 0 -0.889)
			(stroke
				(width 0.1524)
				(type default)
			)
			(layer "F.SilkS")
		)
		(fp_line
			(start 1.733296 -1.549908)
			(end 0.660908 -1.549908)
			(stroke
				(width 0.1524)
				(type default)
			)
			(layer "F.SilkS")
		)
		(fp_line
			(start 1.733296 1.549908)
			(end 1.733296 -1.549908)
			(stroke
				(width 0.1524)
				(type default)
			)
			(layer "F.SilkS")
		)
		(fp_poly
			(pts
				(xy -2.4384 -1.20396) (xy -2.4384 -0.69596) (xy -1.9304 -0.94996)
			)
			(stroke
				(width 0)
				(type default)
			)
			(fill yes)
			(layer "F.SilkS")
		)
		(fp_line
			(start -0.849884 -1.549908)
			(end -0.849884 1.549908)
			(stroke
				(width 0.1)
				(type default)
			)
			(layer "F.Fab")
		)
		(fp_line
			(start -0.849884 1.549908)
			(end 0.849884 1.549908)
			(stroke
				(width 0.1)
				(type default)
			)
			(layer "F.Fab")
		)
		(fp_line
			(start 0.849884 -1.549908)
			(end -0.849884 -1.549908)
			(stroke
				(width 0.1)
				(type default)
			)
			(layer "F.Fab")
		)
		(fp_line
			(start 0.849884 1.549908)
			(end 0.849884 -1.549908)
			(stroke
				(width 0.1)
				(type default)
			)
			(layer "F.Fab")
		)
		(fp_poly
			(pts
				(xy -2.4384 -1.20396) (xy -2.4384 -0.69596) (xy -1.9304 -0.94996)
			)
			(stroke
				(width 0)
				(type default)
			)
			(fill yes)
			(layer "F.Fab")
		)
		(pad "1" smd rect
			(at -1.199896 -0.94996 270)
			(size 0.5588 0.8128)
			(layers "F.Cu" "F.Mask" "F.Paste")
			(net "OCP_V3_2_P3V3_PWRGD")
		)
		(pad "2" smd rect
			(at -1.199896 0 270)
			(size 0.5588 0.8128)
			(layers "F.Cu" "F.Mask" "F.Paste")
			(net "HP_LVC3_OCP_V3_2_P12V_PWRGD_R2")
		)
		(pad "3" smd rect
			(at -1.199896 0.94996 270)
			(size 0.5588 0.8128)
			(layers "F.Cu" "F.Mask" "F.Paste")
			(net "GND")
		)
		(pad "4" smd rect
			(at 1.199896 0.94996 270)
			(size 0.5588 0.8128)
			(layers "F.Cu" "F.Mask" "F.Paste")
			(net "HP_LVC3_OCP_V3_2_PWRGD_R2")
		)
		(pad "5" smd rect
			(at 1.199896 -0.94996 270)
			(size 0.5588 0.8128)
			(layers "F.Cu" "F.Mask" "F.Paste")
			(net "P3V3_AUX")
		)
	)
	(footprint ""
		(layer "F.Cu")
		(at 304.419 -356.997)
		(property "Reference" "PR8007"
			(at 0 0 0)
			(layer "F.SilkS")
			(hide yes)
			(effects
				(font
					(size 1.27 1.27)
				)
			)
		)
		(property "Value" ""
			(at 0 0 0)
			(layer "F.Fab")
			(effects
				(font
					(size 1.27 1.27)
				)
			)
		)
		(duplicate_pad_numbers_are_jumpers no)
		(fp_line
			(start -0.7874 -0.4064)
			(end 0.7874 -0.4064)
			(stroke
				(width 0.1524)
				(type default)
			)
			(layer "F.SilkS")
		)
		(fp_line
			(start -0.7874 0.4064)
			(end -0.7874 -0.4064)
			(stroke
				(width 0.1524)
				(type default)
			)
			(layer "F.SilkS")
		)
		(fp_line
			(start 0.7874 -0.4064)
			(end 0.7874 0.4064)
			(stroke
				(width 0.1524)
				(type default)
			)
			(layer "F.SilkS")
		)
		(fp_line
			(start 0.7874 0.4064)
			(end -0.7874 0.4064)
			(stroke
				(width 0.1524)
				(type default)
			)
			(layer "F.SilkS")
		)
		(fp_line
			(start -0.67945 -0.305054)
			(end -0.12065 -0.305054)
			(stroke
				(width 0.1)
				(type default)
			)
			(layer "F.Fab")
		)
		(fp_line
			(start -0.67945 0.3048)
			(end -0.67945 -0.305054)
			(stroke
				(width 0.1)
				(type default)
			)
			(layer "F.Fab")
		)
		(fp_line
			(start -0.12065 -0.305054)
			(end -0.12065 -0.2794)
			(stroke
				(width 0.1)
				(type default)
			)
			(layer "F.Fab")
		)
		(fp_line
			(start -0.12065 -0.2794)
			(end 0.12065 -0.2794)
			(stroke
				(width 0.1)
				(type default)
			)
			(layer "F.Fab")
		)
		(fp_line
			(start -0.12065 0.2794)
			(end -0.12065 0.3048)
			(stroke
				(width 0.1)
				(type default)
			)
			(layer "F.Fab")
		)
		(fp_line
			(start -0.12065 0.3048)
			(end -0.67945 0.3048)
			(stroke
				(width 0.1)
				(type default)
			)
			(layer "F.Fab")
		)
		(fp_line
			(start 0.120396 0.2794)
			(end -0.12065 0.2794)
			(stroke
				(width 0.1)
				(type default)
			)
			(layer "F.Fab")
		)
		(fp_line
			(start 0.120396 0.3048)
			(end 0.120396 0.2794)
			(stroke
				(width 0.1)
				(type default)
			)
			(layer "F.Fab")
		)
		(fp_line
			(start 0.12065 -0.3048)
			(end 0.67945 -0.3048)
			(stroke
				(width 0.1)
				(type default)
			)
			(layer "F.Fab")
		)
		(fp_line
			(start 0.12065 -0.2794)
			(end 0.12065 -0.3048)
			(stroke
				(width 0.1)
				(type default)
			)
			(layer "F.Fab")
		)
		(fp_line
			(start 0.67945 -0.3048)
			(end 0.67945 0.3048)
			(stroke
				(width 0.1)
				(type default)
			)
			(layer "F.Fab")
		)
		(fp_line
			(start 0.67945 0.3048)
			(end 0.120396 0.3048)
			(stroke
				(width 0.1)
				(type default)
			)
			(layer "F.Fab")
		)
		(pad "1" smd circle
			(at -0.40005 0)
			(size 0 0)
			(layers "F.Cu" "F.Mask" "F.Paste")
			(net "SVID_PVDDCR_CPU1_P0_SVC_R")
		)
		(pad "2" smd circle
			(at 0.40005 0)
			(size 0 0)
			(layers "F.Cu" "F.Mask" "F.Paste")
			(net "SVID_PVDDCR_CPU1_P0_SVC_R1")
		)
	)
	(footprint ""
		(layer "F.Cu")
		(at 169.404792 -101.520498 -90)
		(property "Reference" "R6187"
			(at 0 0 270)
			(layer "F.SilkS")
			(hide yes)
			(effects
				(font
					(size 1.27 1.27)
				)
			)
		)
		(property "Value" ""
			(at 0 0 270)
			(layer "F.Fab")
			(effects
				(font
					(size 1.27 1.27)
				)
			)
		)
		(duplicate_pad_numbers_are_jumpers no)
		(fp_line
			(start -0.7874 0.4064)
			(end -0.7874 -0.4064)
			(stroke
				(width 0.1524)
				(type default)
			)
			(layer "F.SilkS")
		)
		(fp_line
			(start 0.7874 0.4064)
			(end -0.7874 0.4064)
			(stroke
				(width 0.1524)
				(type default)
			)
			(layer "F.SilkS")
		)
		(fp_line
			(start -0.7874 -0.4064)
			(end 0.7874 -0.4064)
			(stroke
				(width 0.1524)
				(type default)
			)
			(layer "F.SilkS")
		)
		(fp_line
			(start 0.7874 -0.4064)
			(end 0.7874 0.4064)
			(stroke
				(width 0.1524)
				(type default)
			)
			(layer "F.SilkS")
		)
		(fp_line
			(start -0.67945 0.3048)
			(end -0.67945 -0.305054)
			(stroke
				(width 0.1)
				(type default)
			)
			(layer "F.Fab")
		)
		(fp_line
			(start -0.12065 0.3048)
			(end -0.67945 0.3048)
			(stroke
				(width 0.1)
				(type default)
			)
			(layer "F.Fab")
		)
		(fp_line
			(start 0.120396 0.3048)
			(end 0.120396 0.2794)
			(stroke
				(width 0.1)
				(type default)
			)
			(layer "F.Fab")
		)
		(fp_line
			(start 0.67945 0.3048)
			(end 0.120396 0.3048)
			(stroke
				(width 0.1)
				(type default)
			)
			(layer "F.Fab")
		)
		(fp_line
			(start -0.12065 0.2794)
			(end -0.12065 0.3048)
			(stroke
				(width 0.1)
				(type default)
			)
			(layer "F.Fab")
		)
		(fp_line
			(start 0.120396 0.2794)
			(end -0.12065 0.2794)
			(stroke
				(width 0.1)
				(type default)
			)
			(layer "F.Fab")
		)
		(fp_line
			(start -0.12065 -0.2794)
			(end 0.12065 -0.2794)
			(stroke
				(width 0.1)
				(type default)
			)
			(layer "F.Fab")
		)
		(fp_line
			(start 0.12065 -0.2794)
			(end 0.12065 -0.3048)
			(stroke
				(width 0.1)
				(type default)
			)
			(layer "F.Fab")
		)
		(fp_line
			(start 0.12065 -0.3048)
			(end 0.67945 -0.3048)
			(stroke
				(width 0.1)
				(type default)
			)
			(layer "F.Fab")
		)
		(fp_line
			(start 0.67945 -0.3048)
			(end 0.67945 0.3048)
			(stroke
				(width 0.1)
				(type default)
			)
			(layer "F.Fab")
		)
		(fp_line
			(start -0.67945 -0.305054)
			(end -0.12065 -0.305054)
			(stroke
				(width 0.1)
				(type default)
			)
			(layer "F.Fab")
		)
		(fp_line
			(start -0.12065 -0.305054)
			(end -0.12065 -0.2794)
			(stroke
				(width 0.1)
				(type default)
			)
			(layer "F.Fab")
		)
		(pad "1" smd circle
			(at -0.40005 0 270)
			(size 0 0)
			(layers "F.Cu" "F.Mask" "F.Paste")
			(net "FM_SEC_MUX_SEL")
		)
		(pad "2" smd circle
			(at 0.40005 0 270)
			(size 0 0)
			(layers "F.Cu" "F.Mask" "F.Paste")
			(net "GND")
		)
	)
	(footprint ""
		(layer "F.Cu")
		(at 58.180732 -343.716864 180)
		(property "Reference" "PC205"
			(at 0 0 180)
			(layer "F.SilkS")
			(hide yes)
			(effects
				(font
					(size 1.27 1.27)
				)
			)
		)
		(property "Value" ""
			(at 0 0 180)
			(layer "F.Fab")
			(effects
				(font
					(size 1.27 1.27)
				)
			)
		)
		(duplicate_pad_numbers_are_jumpers no)
		(fp_line
			(start 0.7874 0.4064)
			(end -0.7874 0.4064)
			(stroke
				(width 0.1524)
				(type default)
			)
			(layer "F.SilkS")
		)
		(fp_line
			(start 0.7874 -0.4064)
			(end 0.7874 0.4064)
			(stroke
				(width 0.1524)
				(type default)
			)
			(layer "F.SilkS")
		)
		(fp_line
			(start -0.7874 0.4064)
			(end -0.7874 -0.4064)
			(stroke
				(width 0.1524)
				(type default)
			)
			(layer "F.SilkS")
		)
		(fp_line
			(start -0.7874 -0.4064)
			(end 0.7874 -0.4064)
			(stroke
				(width 0.1524)
				(type default)
			)
			(layer "F.SilkS")
		)
		(fp_line
			(start 0.67945 0.3048)
			(end 0.120396 0.3048)
			(stroke
				(width 0.1)
				(type default)
			)
			(layer "F.Fab")
		)
		(fp_line
			(start 0.67945 -0.3048)
			(end 0.67945 0.3048)
			(stroke
				(width 0.1)
				(type default)
			)
			(layer "F.Fab")
		)
		(fp_line
			(start 0.12065 -0.2794)
			(end 0.12065 -0.3048)
			(stroke
				(width 0.1)
				(type default)
			)
			(layer "F.Fab")
		)
		(fp_line
			(start 0.12065 -0.3048)
			(end 0.67945 -0.3048)
			(stroke
				(width 0.1)
				(type default)
			)
			(layer "F.Fab")
		)
		(fp_line
			(start 0.120396 0.3048)
			(end 0.120396 0.2794)
			(stroke
				(width 0.1)
				(type default)
			)
			(layer "F.Fab")
		)
		(fp_line
			(start 0.120396 0.2794)
			(end -0.12065 0.2794)
			(stroke
				(width 0.1)
				(type default)
			)
			(layer "F.Fab")
		)
		(fp_line
			(start -0.12065 0.3048)
			(end -0.67945 0.3048)
			(stroke
				(width 0.1)
				(type default)
			)
			(layer "F.Fab")
		)
		(fp_line
			(start -0.12065 0.2794)
			(end -0.12065 0.3048)
			(stroke
				(width 0.1)
				(type default)
			)
			(layer "F.Fab")
		)
		(fp_line
			(start -0.12065 -0.2794)
			(end 0.12065 -0.2794)
			(stroke
				(width 0.1)
				(type default)
			)
			(layer "F.Fab")
		)
		(fp_line
			(start -0.12065 -0.305054)
			(end -0.12065 -0.2794)
			(stroke
				(width 0.1)
				(type default)
			)
			(layer "F.Fab")
		)
		(fp_line
			(start -0.67945 0.3048)
			(end -0.67945 -0.305054)
			(stroke
				(width 0.1)
				(type default)
			)
			(layer "F.Fab")
		)
		(fp_line
			(start -0.67945 -0.305054)
			(end -0.12065 -0.305054)
			(stroke
				(width 0.1)
				(type default)
			)
			(layer "F.Fab")
		)
		(pad "1" smd circle
			(at -0.40005 0 180)
			(size 0 0)
			(layers "F.Cu" "F.Mask" "F.Paste")
			(net "SW_PVDDCR_CPU1_P1_SW4")
		)
		(pad "2" smd circle
			(at 0.40005 0 180)
			(size 0 0)
			(layers "F.Cu" "F.Mask" "F.Paste")
			(net "SW_PVDDCR_CPU1_P1_SW4_RC")
		)
	)
	(footprint ""
		(layer "F.Cu")
		(at 110.856014 -259.845302)
		(property "Reference" "C2266"
			(at 0 0 0)
			(layer "F.SilkS")
			(hide yes)
			(effects
				(font
					(size 1.27 1.27)
				)
			)
		)
		(property "Value" ""
			(at 0 0 0)
			(layer "F.Fab")
			(effects
				(font
					(size 1.27 1.27)
				)
			)
		)
		(duplicate_pad_numbers_are_jumpers no)
		(fp_line
			(start -0.7874 -0.4064)
			(end 0.7874 -0.4064)
			(stroke
				(width 0.1524)
				(type default)
			)
			(layer "F.SilkS")
		)
		(fp_line
			(start -0.7874 0.4064)
			(end -0.7874 -0.4064)
			(stroke
				(width 0.1524)
				(type default)
			)
			(layer "F.SilkS")
		)
		(fp_line
			(start 0.7874 -0.4064)
			(end 0.7874 0.4064)
			(stroke
				(width 0.1524)
				(type default)
			)
			(layer "F.SilkS")
		)
		(fp_line
			(start 0.7874 0.4064)
			(end -0.7874 0.4064)
			(stroke
				(width 0.1524)
				(type default)
			)
			(layer "F.SilkS")
		)
		(fp_line
			(start -0.67945 -0.305054)
			(end -0.12065 -0.305054)
			(stroke
				(width 0.1)
				(type default)
			)
			(layer "F.Fab")
		)
		(fp_line
			(start -0.67945 0.3048)
			(end -0.67945 -0.305054)
			(stroke
				(width 0.1)
				(type default)
			)
			(layer "F.Fab")
		)
		(fp_line
			(start -0.12065 -0.305054)
			(end -0.12065 -0.2794)
			(stroke
				(width 0.1)
				(type default)
			)
			(layer "F.Fab")
		)
		(fp_line
			(start -0.12065 -0.2794)
			(end 0.12065 -0.2794)
			(stroke
				(width 0.1)
				(type default)
			)
			(layer "F.Fab")
		)
		(fp_line
			(start -0.12065 0.2794)
			(end -0.12065 0.3048)
			(stroke
				(width 0.1)
				(type default)
			)
			(layer "F.Fab")
		)
		(fp_line
			(start -0.12065 0.3048)
			(end -0.67945 0.3048)
			(stroke
				(width 0.1)
				(type default)
			)
			(layer "F.Fab")
		)
		(fp_line
			(start 0.120396 0.2794)
			(end -0.12065 0.2794)
			(stroke
				(width 0.1)
				(type default)
			)
			(layer "F.Fab")
		)
		(fp_line
			(start 0.120396 0.3048)
			(end 0.120396 0.2794)
			(stroke
				(width 0.1)
				(type default)
			)
			(layer "F.Fab")
		)
		(fp_line
			(start 0.12065 -0.3048)
			(end 0.67945 -0.3048)
			(stroke
				(width 0.1)
				(type default)
			)
			(layer "F.Fab")
		)
		(fp_line
			(start 0.12065 -0.2794)
			(end 0.12065 -0.3048)
			(stroke
				(width 0.1)
				(type default)
			)
			(layer "F.Fab")
		)
		(fp_line
			(start 0.67945 -0.3048)
			(end 0.67945 0.3048)
			(stroke
				(width 0.1)
				(type default)
			)
			(layer "F.Fab")
		)
		(fp_line
			(start 0.67945 0.3048)
			(end 0.120396 0.3048)
			(stroke
				(width 0.1)
				(type default)
			)
			(layer "F.Fab")
		)
		(pad "1" smd circle
			(at -0.40005 0)
			(size 0 0)
			(layers "F.Cu" "F.Mask" "F.Paste")
			(net "PVDD11_S3_P1")
		)
		(pad "2" smd circle
			(at 0.40005 0)
			(size 0 0)
			(layers "F.Cu" "F.Mask" "F.Paste")
			(net "GND")
		)
	)
	(footprint ""
		(layer "F.Cu")
		(at 318.623696 -383.88163 -90)
		(property "Reference" "C912"
			(at 0 0 270)
			(layer "F.SilkS")
			(hide yes)
			(effects
				(font
					(size 1.27 1.27)
				)
			)
		)
		(property "Value" ""
			(at 0 0 270)
			(layer "F.Fab")
			(effects
				(font
					(size 1.27 1.27)
				)
			)
		)
		(duplicate_pad_numbers_are_jumpers no)
		(fp_line
			(start -0.299974 0.150114)
			(end -0.299974 -0.150114)
			(stroke
				(width 0.1)
				(type default)
			)
			(layer "F.Fab")
		)
		(fp_line
			(start 0.299974 0.150114)
			(end -0.299974 0.150114)
			(stroke
				(width 0.1)
				(type default)
			)
			(layer "F.Fab")
		)
		(fp_line
			(start -0.299974 -0.150114)
			(end 0.299974 -0.150114)
			(stroke
				(width 0.1)
				(type default)
			)
			(layer "F.Fab")
		)
		(fp_line
			(start 0.299974 -0.150114)
			(end 0.299974 0.150114)
			(stroke
				(width 0.1)
				(type default)
			)
			(layer "F.Fab")
		)
		(pad "1" smd rect
			(at -0.2667 0 270)
			(size 0.3048 0.381)
			(layers "F.Cu" "F.Mask" "F.Paste")
			(net "P5E_CPU0_P0_TX_C_DN<10>")
		)
		(pad "2" smd rect
			(at 0.2667 0 270)
			(size 0.3048 0.381)
			(layers "F.Cu" "F.Mask" "F.Paste")
			(net "P5E_CPU0_P0_TX_DN<10>")
		)
	)
	(footprint ""
		(layer "F.Cu")
		(at 193.954908 -153.774902)
		(property "Reference" "H126"
			(at 6.2738 -0.68453 0)
			(unlocked yes)
			(layer "F.SilkS")
			(effects
				(font
					(size 0.7874 0.5842)
					(thickness 0.1524)
				)
				(justify left)
			)
		)
		(property "Value" ""
			(at 0 0 0)
			(layer "F.Fab")
			(effects
				(font
					(size 1.27 1.27)
				)
			)
		)
		(duplicate_pad_numbers_are_jumpers no)
		(fp_circle
			(center 0 0)
			(end 5.8166 0)
			(stroke
				(width 0.1524)
				(type default)
			)
			(fill no)
			(layer "F.SilkS")
		)
		(fp_circle
			(center 0 0)
			(end 5.8166 0)
			(stroke
				(width 0.1524)
				(type default)
			)
			(fill no)
			(layer "B.SilkS")
		)
		(fp_circle
			(center 0 0)
			(end 5.8166 0)
			(stroke
				(width 0.1)
				(type default)
			)
			(fill no)
			(layer "B.Fab")
		)
		(fp_circle
			(center 0 0)
			(end 5.8166 0)
			(stroke
				(width 0.1)
				(type default)
			)
			(fill no)
			(layer "F.Fab")
		)
		(pad "" np_thru_hole circle
			(at 0 0)
			(size 10.0076 10.0076)
			(drill 10.0076)
			(layers "*.Cu" "*.Mask")
			(clearance 0.381)
			(thermal_gap 0.381)
		)
	)
)
